(kicad_pcb
	(version 20260206)
	(generator "pcbnew")
	(generator_version "10.0")
	(general
		(thickness 1.6)
		(legacy_teardrops no)
	)
	(paper "A4")
	(title_block
		(title "01162023_DA0F0TEBIF0_F0T_Expander_BD_F_brd_V02_OCP.brd")
		(comment 1 "Grand Teton / footprints 1272-1277 of 9728")
	)
	(layers
		(0 "F.Cu" signal "TOP")
		(4 "In1.Cu" signal "GND")
		(6 "In2.Cu" signal "VCC")
		(8 "In3.Cu" signal "VCC1")
		(10 "In4.Cu" signal "GND1")
		(12 "In5.Cu" signal "IN1")
		(14 "In6.Cu" signal "GND2")
		(16 "In7.Cu" signal "IN2")
		(18 "In8.Cu" signal "GND3")
		(20 "In9.Cu" signal "IN3")
		(22 "In10.Cu" signal "GND4")
		(24 "In11.Cu" signal "IN4")
		(26 "In12.Cu" signal "GND5")
		(28 "In13.Cu" signal "IN5")
		(30 "In14.Cu" signal "GND6")
		(32 "In15.Cu" signal "IN6")
		(34 "In16.Cu" signal "GND7")
		(2 "B.Cu" signal "BOTTOM")
		(9 "F.Adhes" user "F.Adhesive")
		(11 "B.Adhes" user "B.Adhesive")
		(13 "F.Paste" user "Package Geometry/Pastemask Top")
		(15 "B.Paste" user "Package Geometry/Pastemask Bottom")
		(5 "F.SilkS" user "Ref Des/Silkscreen Top")
		(7 "B.SilkS" user "Ref Des/Silkscreen Bottom")
		(1 "F.Mask" user "Board Geometry/Soldermask Top")
		(3 "B.Mask" user "Board Geometry/Soldermask Bottom")
		(17 "Dwgs.User" user "User.Drawings")
		(19 "Cmts.User" user "User.Comments")
		(21 "Eco1.User" user "User.Eco1")
		(23 "Eco2.User" user "User.Eco2")
		(25 "Edge.Cuts" user "Board Geometry/Outline")
		(27 "Margin" user)
		(31 "F.CrtYd" user "Package Geometry/Place Bound Top")
		(29 "B.CrtYd" user "Package Geometry/Place Bound Bottom")
		(35 "F.Fab" user "Ref Des/Assembly Top")
		(33 "B.Fab" user "Ref Des/Assembly Bottom")
	)
	(footprint ""
		(layer "F.Cu")
		(at 419.02253 -44.341542 90)
		(property "Reference" "R668"
			(at 0 0 90)
			(layer "F.SilkS")
			(hide yes)
			(effects
				(font
					(size 1.27 1.27)
				)
			)
		)
		(property "Value" ""
			(at 0 0 90)
			(layer "F.Fab")
			(effects
				(font
					(size 1.27 1.27)
				)
			)
		)
		(duplicate_pad_numbers_are_jumpers no)
		(fp_line
			(start 0.7874 -0.4064)
			(end 0.7874 0.4064)
			(stroke
				(width 0.1524)
				(type default)
			)
			(layer "F.SilkS")
		)
		(fp_line
			(start -0.7874 -0.4064)
			(end 0.7874 -0.4064)
			(stroke
				(width 0.1524)
				(type default)
			)
			(layer "F.SilkS")
		)
		(fp_line
			(start 0.7874 0.4064)
			(end -0.7874 0.4064)
			(stroke
				(width 0.1524)
				(type default)
			)
			(layer "F.SilkS")
		)
		(fp_line
			(start -0.7874 0.4064)
			(end -0.7874 -0.4064)
			(stroke
				(width 0.1524)
				(type default)
			)
			(layer "F.SilkS")
		)
		(fp_line
			(start -0.12065 -0.305054)
			(end -0.12065 -0.2794)
			(stroke
				(width 0.1)
				(type default)
			)
			(layer "F.Fab")
		)
		(fp_line
			(start -0.67945 -0.305054)
			(end -0.12065 -0.305054)
			(stroke
				(width 0.1)
				(type default)
			)
			(layer "F.Fab")
		)
		(fp_line
			(start 0.67945 -0.3048)
			(end 0.67945 0.3048)
			(stroke
				(width 0.1)
				(type default)
			)
			(layer "F.Fab")
		)
		(fp_line
			(start 0.12065 -0.3048)
			(end 0.67945 -0.3048)
			(stroke
				(width 0.1)
				(type default)
			)
			(layer "F.Fab")
		)
		(fp_line
			(start 0.12065 -0.2794)
			(end 0.12065 -0.3048)
			(stroke
				(width 0.1)
				(type default)
			)
			(layer "F.Fab")
		)
		(fp_line
			(start -0.12065 -0.2794)
			(end 0.12065 -0.2794)
			(stroke
				(width 0.1)
				(type default)
			)
			(layer "F.Fab")
		)
		(fp_line
			(start 0.120396 0.2794)
			(end -0.12065 0.2794)
			(stroke
				(width 0.1)
				(type default)
			)
			(layer "F.Fab")
		)
		(fp_line
			(start -0.12065 0.2794)
			(end -0.12065 0.3048)
			(stroke
				(width 0.1)
				(type default)
			)
			(layer "F.Fab")
		)
		(fp_line
			(start 0.67945 0.3048)
			(end 0.120396 0.3048)
			(stroke
				(width 0.1)
				(type default)
			)
			(layer "F.Fab")
		)
		(fp_line
			(start 0.120396 0.3048)
			(end 0.120396 0.2794)
			(stroke
				(width 0.1)
				(type default)
			)
			(layer "F.Fab")
		)
		(fp_line
			(start -0.12065 0.3048)
			(end -0.67945 0.3048)
			(stroke
				(width 0.1)
				(type default)
			)
			(layer "F.Fab")
		)
		(fp_line
			(start -0.67945 0.3048)
			(end -0.67945 -0.305054)
			(stroke
				(width 0.1)
				(type default)
			)
			(layer "F.Fab")
		)
		(pad "1" smd circle
			(at -0.40005 0 90)
			(size 0 0)
			(layers "F.Cu" "F.Mask" "F.Paste")
			(net "P12V_SSD14")
		)
		(pad "2" smd circle
			(at 0.40005 0 90)
			(size 0 0)
			(layers "F.Cu" "F.Mask" "F.Paste")
			(net "P12V_SSD14_VIN_N")
		)
	)
	(footprint ""
		(layer "F.Cu")
		(at 359.385362 -118.343426 -90)
		(property "Reference" "R6044"
			(at 0 0 270)
			(layer "F.SilkS")
			(hide yes)
			(effects
				(font
					(size 1.27 1.27)
				)
			)
		)
		(property "Value" ""
			(at 0 0 270)
			(layer "F.Fab")
			(effects
				(font
					(size 1.27 1.27)
				)
			)
		)
		(duplicate_pad_numbers_are_jumpers no)
		(fp_line
			(start -0.7874 0.4064)
			(end -0.7874 -0.4064)
			(stroke
				(width 0.1524)
				(type default)
			)
			(layer "F.SilkS")
		)
		(fp_line
			(start 0.7874 0.4064)
			(end -0.7874 0.4064)
			(stroke
				(width 0.1524)
				(type default)
			)
			(layer "F.SilkS")
		)
		(fp_line
			(start -0.7874 -0.4064)
			(end 0.7874 -0.4064)
			(stroke
				(width 0.1524)
				(type default)
			)
			(layer "F.SilkS")
		)
		(fp_line
			(start 0.7874 -0.4064)
			(end 0.7874 0.4064)
			(stroke
				(width 0.1524)
				(type default)
			)
			(layer "F.SilkS")
		)
		(fp_line
			(start -0.67945 0.3048)
			(end -0.67945 -0.305054)
			(stroke
				(width 0.1)
				(type default)
			)
			(layer "F.Fab")
		)
		(fp_line
			(start -0.12065 0.3048)
			(end -0.67945 0.3048)
			(stroke
				(width 0.1)
				(type default)
			)
			(layer "F.Fab")
		)
		(fp_line
			(start 0.120396 0.3048)
			(end 0.120396 0.2794)
			(stroke
				(width 0.1)
				(type default)
			)
			(layer "F.Fab")
		)
		(fp_line
			(start 0.67945 0.3048)
			(end 0.120396 0.3048)
			(stroke
				(width 0.1)
				(type default)
			)
			(layer "F.Fab")
		)
		(fp_line
			(start -0.12065 0.2794)
			(end -0.12065 0.3048)
			(stroke
				(width 0.1)
				(type default)
			)
			(layer "F.Fab")
		)
		(fp_line
			(start 0.120396 0.2794)
			(end -0.12065 0.2794)
			(stroke
				(width 0.1)
				(type default)
			)
			(layer "F.Fab")
		)
		(fp_line
			(start -0.12065 -0.2794)
			(end 0.12065 -0.2794)
			(stroke
				(width 0.1)
				(type default)
			)
			(layer "F.Fab")
		)
		(fp_line
			(start 0.12065 -0.2794)
			(end 0.12065 -0.3048)
			(stroke
				(width 0.1)
				(type default)
			)
			(layer "F.Fab")
		)
		(fp_line
			(start 0.12065 -0.3048)
			(end 0.67945 -0.3048)
			(stroke
				(width 0.1)
				(type default)
			)
			(layer "F.Fab")
		)
		(fp_line
			(start 0.67945 -0.3048)
			(end 0.67945 0.3048)
			(stroke
				(width 0.1)
				(type default)
			)
			(layer "F.Fab")
		)
		(fp_line
			(start -0.67945 -0.305054)
			(end -0.12065 -0.305054)
			(stroke
				(width 0.1)
				(type default)
			)
			(layer "F.Fab")
		)
		(fp_line
			(start -0.12065 -0.305054)
			(end -0.12065 -0.2794)
			(stroke
				(width 0.1)
				(type default)
			)
			(layer "F.Fab")
		)
		(pad "1" smd circle
			(at -0.40005 0 270)
			(size 0 0)
			(layers "F.Cu" "F.Mask" "F.Paste")
			(net "P3V3_AUX")
		)
		(pad "2" smd circle
			(at 0.40005 0 270)
			(size 0 0)
			(layers "F.Cu" "F.Mask" "F.Paste")
			(net "PWRGD_P3V3_NIC6_D")
		)
	)
	(footprint ""
		(layer "F.Cu")
		(at 82.11439 -140.134848 -90)
		(property "Reference" "R95"
			(at 0 0 270)
			(layer "F.SilkS")
			(hide yes)
			(effects
				(font
					(size 1.27 1.27)
				)
			)
		)
		(property "Value" ""
			(at 0 0 270)
			(layer "F.Fab")
			(effects
				(font
					(size 1.27 1.27)
				)
			)
		)
		(duplicate_pad_numbers_are_jumpers no)
		(fp_line
			(start -0.7874 0.4064)
			(end -0.7874 -0.4064)
			(stroke
				(width 0.1524)
				(type default)
			)
			(layer "F.SilkS")
		)
		(fp_line
			(start 0.7874 0.4064)
			(end -0.7874 0.4064)
			(stroke
				(width 0.1524)
				(type default)
			)
			(layer "F.SilkS")
		)
		(fp_line
			(start -0.7874 -0.4064)
			(end 0.7874 -0.4064)
			(stroke
				(width 0.1524)
				(type default)
			)
			(layer "F.SilkS")
		)
		(fp_line
			(start 0.7874 -0.4064)
			(end 0.7874 0.4064)
			(stroke
				(width 0.1524)
				(type default)
			)
			(layer "F.SilkS")
		)
		(fp_line
			(start -0.67945 0.3048)
			(end -0.67945 -0.305054)
			(stroke
				(width 0.1)
				(type default)
			)
			(layer "F.Fab")
		)
		(fp_line
			(start -0.12065 0.3048)
			(end -0.67945 0.3048)
			(stroke
				(width 0.1)
				(type default)
			)
			(layer "F.Fab")
		)
		(fp_line
			(start 0.120396 0.3048)
			(end 0.120396 0.2794)
			(stroke
				(width 0.1)
				(type default)
			)
			(layer "F.Fab")
		)
		(fp_line
			(start 0.67945 0.3048)
			(end 0.120396 0.3048)
			(stroke
				(width 0.1)
				(type default)
			)
			(layer "F.Fab")
		)
		(fp_line
			(start -0.12065 0.2794)
			(end -0.12065 0.3048)
			(stroke
				(width 0.1)
				(type default)
			)
			(layer "F.Fab")
		)
		(fp_line
			(start 0.120396 0.2794)
			(end -0.12065 0.2794)
			(stroke
				(width 0.1)
				(type default)
			)
			(layer "F.Fab")
		)
		(fp_line
			(start -0.12065 -0.2794)
			(end 0.12065 -0.2794)
			(stroke
				(width 0.1)
				(type default)
			)
			(layer "F.Fab")
		)
		(fp_line
			(start 0.12065 -0.2794)
			(end 0.12065 -0.3048)
			(stroke
				(width 0.1)
				(type default)
			)
			(layer "F.Fab")
		)
		(fp_line
			(start 0.12065 -0.3048)
			(end 0.67945 -0.3048)
			(stroke
				(width 0.1)
				(type default)
			)
			(layer "F.Fab")
		)
		(fp_line
			(start 0.67945 -0.3048)
			(end 0.67945 0.3048)
			(stroke
				(width 0.1)
				(type default)
			)
			(layer "F.Fab")
		)
		(fp_line
			(start -0.67945 -0.305054)
			(end -0.12065 -0.305054)
			(stroke
				(width 0.1)
				(type default)
			)
			(layer "F.Fab")
		)
		(fp_line
			(start -0.12065 -0.305054)
			(end -0.12065 -0.2794)
			(stroke
				(width 0.1)
				(type default)
			)
			(layer "F.Fab")
		)
		(pad "1" smd circle
			(at -0.40005 0 270)
			(size 0 0)
			(layers "F.Cu" "F.Mask" "F.Paste")
			(net "P3V3_AUX")
		)
		(pad "2" smd circle
			(at 0.40005 0 270)
			(size 0 0)
			(layers "F.Cu" "F.Mask" "F.Paste")
			(net "HP_NIC1_EN")
		)
	)
	(footprint ""
		(layer "F.Cu")
		(at 275.992336 -32.739584 180)
		(property "Reference" "C497"
			(at 0 0 180)
			(layer "F.SilkS")
			(hide yes)
			(effects
				(font
					(size 1.27 1.27)
				)
			)
		)
		(property "Value" ""
			(at 0 0 180)
			(layer "F.Fab")
			(effects
				(font
					(size 1.27 1.27)
				)
			)
		)
		(duplicate_pad_numbers_are_jumpers no)
		(fp_line
			(start 0.299974 0.150114)
			(end -0.299974 0.150114)
			(stroke
				(width 0.1)
				(type default)
			)
			(layer "F.Fab")
		)
		(fp_line
			(start 0.299974 -0.150114)
			(end 0.299974 0.150114)
			(stroke
				(width 0.1)
				(type default)
			)
			(layer "F.Fab")
		)
		(fp_line
			(start -0.299974 0.150114)
			(end -0.299974 -0.150114)
			(stroke
				(width 0.1)
				(type default)
			)
			(layer "F.Fab")
		)
		(fp_line
			(start -0.299974 -0.150114)
			(end 0.299974 -0.150114)
			(stroke
				(width 0.1)
				(type default)
			)
			(layer "F.Fab")
		)
		(pad "1" smd rect
			(at -0.2667 0 180)
			(size 0.3048 0.381)
			(layers "F.Cu" "F.Mask" "F.Paste")
			(net "P5E_PEX2_STN2_TX_DP<42>")
		)
		(pad "2" smd rect
			(at 0.2667 0 180)
			(size 0.3048 0.381)
			(layers "F.Cu" "F.Mask" "F.Paste")
			(net "P5E_PEX2_STN2_TX_C_DP<42>")
		)
	)
	(footprint ""
		(layer "F.Cu")
		(at 229.711504 -155.940506 -90)
		(property "Reference" "R1206"
			(at 0 0 270)
			(layer "F.SilkS")
			(hide yes)
			(effects
				(font
					(size 1.27 1.27)
				)
			)
		)
		(property "Value" ""
			(at 0 0 270)
			(layer "F.Fab")
			(effects
				(font
					(size 1.27 1.27)
				)
			)
		)
		(duplicate_pad_numbers_are_jumpers no)
		(fp_line
			(start -0.7874 -0.4064)
			(end 0.7874 -0.4064)
			(stroke
				(width 0.1524)
				(type default)
			)
			(layer "F.SilkS")
		)
		(fp_line
			(start -0.67945 0.3048)
			(end -0.67945 -0.305054)
			(stroke
				(width 0.1)
				(type default)
			)
			(layer "F.Fab")
		)
		(fp_line
			(start -0.12065 0.3048)
			(end -0.67945 0.3048)
			(stroke
				(width 0.1)
				(type default)
			)
			(layer "F.Fab")
		)
		(fp_line
			(start 0.120396 0.3048)
			(end 0.120396 0.2794)
			(stroke
				(width 0.1)
				(type default)
			)
			(layer "F.Fab")
		)
		(fp_line
			(start 0.67945 0.3048)
			(end 0.120396 0.3048)
			(stroke
				(width 0.1)
				(type default)
			)
			(layer "F.Fab")
		)
		(fp_line
			(start -0.12065 0.2794)
			(end -0.12065 0.3048)
			(stroke
				(width 0.1)
				(type default)
			)
			(layer "F.Fab")
		)
		(fp_line
			(start 0.120396 0.2794)
			(end -0.12065 0.2794)
			(stroke
				(width 0.1)
				(type default)
			)
			(layer "F.Fab")
		)
		(fp_line
			(start -0.12065 -0.2794)
			(end 0.12065 -0.2794)
			(stroke
				(width 0.1)
				(type default)
			)
			(layer "F.Fab")
		)
		(fp_line
			(start 0.12065 -0.2794)
			(end 0.12065 -0.3048)
			(stroke
				(width 0.1)
				(type default)
			)
			(layer "F.Fab")
		)
		(fp_line
			(start 0.12065 -0.3048)
			(end 0.67945 -0.3048)
			(stroke
				(width 0.1)
				(type default)
			)
			(layer "F.Fab")
		)
		(fp_line
			(start 0.67945 -0.3048)
			(end 0.67945 0.3048)
			(stroke
				(width 0.1)
				(type default)
			)
			(layer "F.Fab")
		)
		(fp_line
			(start -0.67945 -0.305054)
			(end -0.12065 -0.305054)
			(stroke
				(width 0.1)
				(type default)
			)
			(layer "F.Fab")
		)
		(fp_line
			(start -0.12065 -0.305054)
			(end -0.12065 -0.2794)
			(stroke
				(width 0.1)
				(type default)
			)
			(layer "F.Fab")
		)
		(pad "1" smd circle
			(at -0.40005 0 270)
			(size 0 0)
			(layers "F.Cu" "F.Mask" "F.Paste")
			(net "CLK_100M_PEX0_REF_R_DN")
		)
		(pad "2" smd circle
			(at 0.40005 0 270)
			(size 0 0)
			(layers "F.Cu" "F.Mask" "F.Paste")
			(net "CLK_100M_PEX0_REF_DN")
		)
	)
	(footprint ""
		(layer "F.Cu")
		(at 355.009196 -27.04973 180)
		(property "Reference" "C2775"
			(at 0 0 180)
			(layer "F.SilkS")
			(hide yes)
			(effects
				(font
					(size 1.27 1.27)
				)
			)
		)
		(property "Value" ""
			(at 0 0 180)
			(layer "F.Fab")
			(effects
				(font
					(size 1.27 1.27)
				)
			)
		)
		(duplicate_pad_numbers_are_jumpers no)
		(fp_line
			(start 0.7874 0.4064)
			(end -0.7874 0.4064)
			(stroke
				(width 0.1524)
				(type default)
			)
			(layer "F.SilkS")
		)
		(fp_line
			(start 0.7874 -0.4064)
			(end 0.7874 0.4064)
			(stroke
				(width 0.1524)
				(type default)
			)
			(layer "F.SilkS")
		)
		(fp_line
			(start -0.7874 0.4064)
			(end -0.7874 -0.4064)
			(stroke
				(width 0.1524)
				(type default)
			)
			(layer "F.SilkS")
		)
		(fp_line
			(start -0.7874 -0.4064)
			(end 0.7874 -0.4064)
			(stroke
				(width 0.1524)
				(type default)
			)
			(layer "F.SilkS")
		)
		(fp_line
			(start 0.67945 0.3048)
			(end 0.120396 0.3048)
			(stroke
				(width 0.1)
				(type default)
			)
			(layer "F.Fab")
		)
		(fp_line
			(start 0.67945 -0.3048)
			(end 0.67945 0.3048)
			(stroke
				(width 0.1)
				(type default)
			)
			(layer "F.Fab")
		)
		(fp_line
			(start 0.12065 -0.2794)
			(end 0.12065 -0.3048)
			(stroke
				(width 0.1)
				(type default)
			)
			(layer "F.Fab")
		)
		(fp_line
			(start 0.12065 -0.3048)
			(end 0.67945 -0.3048)
			(stroke
				(width 0.1)
				(type default)
			)
			(layer "F.Fab")
		)
		(fp_line
			(start 0.120396 0.3048)
			(end 0.120396 0.2794)
			(stroke
				(width 0.1)
				(type default)
			)
			(layer "F.Fab")
		)
		(fp_line
			(start 0.120396 0.2794)
			(end -0.12065 0.2794)
			(stroke
				(width 0.1)
				(type default)
			)
			(layer "F.Fab")
		)
		(fp_line
			(start -0.12065 0.3048)
			(end -0.67945 0.3048)
			(stroke
				(width 0.1)
				(type default)
			)
			(layer "F.Fab")
		)
		(fp_line
			(start -0.12065 0.2794)
			(end -0.12065 0.3048)
			(stroke
				(width 0.1)
				(type default)
			)
			(layer "F.Fab")
		)
		(fp_line
			(start -0.12065 -0.2794)
			(end 0.12065 -0.2794)
			(stroke
				(width 0.1)
				(type default)
			)
			(layer "F.Fab")
		)
		(fp_line
			(start -0.12065 -0.305054)
			(end -0.12065 -0.2794)
			(stroke
				(width 0.1)
				(type default)
			)
			(layer "F.Fab")
		)
		(fp_line
			(start -0.67945 0.3048)
			(end -0.67945 -0.305054)
			(stroke
				(width 0.1)
				(type default)
			)
			(layer "F.Fab")
		)
		(fp_line
			(start -0.67945 -0.305054)
			(end -0.12065 -0.305054)
			(stroke
				(width 0.1)
				(type default)
			)
			(layer "F.Fab")
		)
		(pad "1" smd circle
			(at -0.40005 0 180)
			(size 0 0)
			(layers "F.Cu" "F.Mask" "F.Paste")
			(net "PRSNT_SSD12_R_N")
		)
		(pad "2" smd circle
			(at 0.40005 0 180)
			(size 0 0)
			(layers "F.Cu" "F.Mask" "F.Paste")
			(net "GND")
		)
	)
)
